# S9S_MB_2U (Grand Teton) — schematic netlist excerpt (pin names and nets, part order shuffled) for the footprints in the layout excerpt that follows; sources: Cadence DE-HDL packaged netlist, KiCad conversion of 03242023_DA0F0TMBIJ0_F0T_Motherboard_J_brd_V01_OCP.brd

PR1803  Q_RES  3.3 1% CHIP  pkg 0402LF  page 290 : A = SW_PVCCFA_EHV_FIVRA_CPU1_BOOT4 ; B = SW_PVCCFA_EHV_FIVRA_CPU1_BOOT4_
R3272  Q_RES  1K 1% EMPTY  pkg 0402LF  page 166 : A = FM_P2E_EQA1 ; B = GND

(kicad_pcb
	(version 20260206)
	(generator "pcbnew")
	(generator_version "10.0")
	(general
		(thickness 1.6)
		(legacy_teardrops no)
	)
	(paper "A4")
	(title_block
		(title "03242023_DA0F0TMBIJ0_F0T_Motherboard_J_brd_V01_OCP.brd")
		(comment 1 "Grand Teton / footprints 3301-3302 of 6105")
	)
	(layers
		(0 "F.Cu" signal "TOP")
		(4 "In1.Cu" signal "GND")
		(6 "In2.Cu" signal "IN1")
		(8 "In3.Cu" signal "GND1")
		(10 "In4.Cu" signal "IN2")
		(12 "In5.Cu" signal "GND2")
		(14 "In6.Cu" signal "IN3")
		(16 "In7.Cu" signal "GND3")
		(18 "In8.Cu" signal "VCC")
		(20 "In9.Cu" signal "VCC1")
		(22 "In10.Cu" signal "GND4")
		(24 "In11.Cu" signal "IN4")
		(26 "In12.Cu" signal "GND5")
		(28 "In13.Cu" signal "IN5")
		(30 "In14.Cu" signal "GND6")
		(32 "In15.Cu" signal "IN6")
		(34 "In16.Cu" signal "GND7")
		(2 "B.Cu" signal "BOTTOM")
		(9 "F.Adhes" user "F.Adhesive")
		(11 "B.Adhes" user "B.Adhesive")
		(13 "F.Paste" user "Package Geometry/Pastemask Top")
		(15 "B.Paste" user "Package Geometry/Pastemask Bottom")
		(5 "F.SilkS" user "Ref Des/Silkscreen Top")
		(7 "B.SilkS" user "Ref Des/Silkscreen Bottom")
		(1 "F.Mask" user "Board Geometry/Soldermask Top")
		(3 "B.Mask" user "Board Geometry/Soldermask Bottom")
		(17 "Dwgs.User" user "User.Drawings")
		(19 "Cmts.User" user "User.Comments")
		(21 "Eco1.User" user "User.Eco1")
		(23 "Eco2.User" user "User.Eco2")
		(25 "Edge.Cuts" user "Board Geometry/Outline")
		(27 "Margin" user)
		(31 "F.CrtYd" user "Package Geometry/Place Bound Top")
		(29 "B.CrtYd" user "Package Geometry/Place Bound Bottom")
		(35 "F.Fab" user "Ref Des/Assembly Top")
		(33 "B.Fab" user "Ref Des/Assembly Bottom")
	)
	(footprint ""
		(layer "F.Cu")
		(at 42.324274 -358.38003 90)
		(property "Reference" "PR1803"
			(at 0 0 90)
			(layer "F.SilkS")
			(hide yes)
			(effects
				(font
					(size 1.27 1.27)
				)
			)
		)
		(property "Value" ""
			(at 0 0 90)
			(layer "F.Fab")
			(effects
				(font
					(size 1.27 1.27)
				)
			)
		)
		(duplicate_pad_numbers_are_jumpers no)
		(fp_line
			(start 0.7874 -0.4064)
			(end 0.7874 0.4064)
			(stroke
				(width 0.1524)
				(type default)
			)
			(layer "F.SilkS")
		)
		(fp_line
			(start -0.7874 -0.4064)
			(end 0.7874 -0.4064)
			(stroke
				(width 0.1524)
				(type default)
			)
			(layer "F.SilkS")
		)
		(fp_line
			(start 0.7874 0.4064)
			(end -0.7874 0.4064)
			(stroke
				(width 0.1524)
				(type default)
			)
			(layer "F.SilkS")
		)
		(fp_line
			(start -0.7874 0.4064)
			(end -0.7874 -0.4064)
			(stroke
				(width 0.1524)
				(type default)
			)
			(layer "F.SilkS")
		)
		(fp_line
			(start -0.12065 -0.305054)
			(end -0.12065 -0.2794)
			(stroke
				(width 0.1)
				(type default)
			)
			(layer "F.Fab")
		)
		(fp_line
			(start -0.67945 -0.305054)
			(end -0.12065 -0.305054)
			(stroke
				(width 0.1)
				(type default)
			)
			(layer "F.Fab")
		)
		(fp_line
			(start 0.67945 -0.3048)
			(end 0.67945 0.3048)
			(stroke
				(width 0.1)
				(type default)
			)
			(layer "F.Fab")
		)
		(fp_line
			(start 0.12065 -0.3048)
			(end 0.67945 -0.3048)
			(stroke
				(width 0.1)
				(type default)
			)
			(layer "F.Fab")
		)
		(fp_line
			(start 0.12065 -0.2794)
			(end 0.12065 -0.3048)
			(stroke
				(width 0.1)
				(type default)
			)
			(layer "F.Fab")
		)
		(fp_line
			(start -0.12065 -0.2794)
			(end 0.12065 -0.2794)
			(stroke
				(width 0.1)
				(type default)
			)
			(layer "F.Fab")
		)
		(fp_line
			(start 0.120396 0.2794)
			(end -0.12065 0.2794)
			(stroke
				(width 0.1)
				(type default)
			)
			(layer "F.Fab")
		)
		(fp_line
			(start -0.12065 0.2794)
			(end -0.12065 0.3048)
			(stroke
				(width 0.1)
				(type default)
			)
			(layer "F.Fab")
		)
		(fp_line
			(start 0.67945 0.3048)
			(end 0.120396 0.3048)
			(stroke
				(width 0.1)
				(type default)
			)
			(layer "F.Fab")
		)
		(fp_line
			(start 0.120396 0.3048)
			(end 0.120396 0.2794)
			(stroke
				(width 0.1)
				(type default)
			)
			(layer "F.Fab")
		)
		(fp_line
			(start -0.12065 0.3048)
			(end -0.67945 0.3048)
			(stroke
				(width 0.1)
				(type default)
			)
			(layer "F.Fab")
		)
		(fp_line
			(start -0.67945 0.3048)
			(end -0.67945 -0.305054)
			(stroke
				(width 0.1)
				(type default)
			)
			(layer "F.Fab")
		)
		(pad "1" smd circle
			(at -0.40005 0 90)
			(size 0 0)
			(layers "F.Cu" "F.Mask" "F.Paste")
			(net "SW_PVCCFA_EHV_FIVRA_CPU1_BOOT4")
		)
		(pad "2" smd circle
			(at 0.40005 0 90)
			(size 0 0)
			(layers "F.Cu" "F.Mask" "F.Paste")
			(net "SW_PVCCFA_EHV_FIVRA_CPU1_BOOT4_")
		)
	)
	(footprint ""
		(layer "F.Cu")
		(at 15.436596 -394.231876 180)
		(property "Reference" "R3272"
			(at 0 0 180)
			(layer "F.SilkS")
			(hide yes)
			(effects
				(font
					(size 1.27 1.27)
				)
			)
		)
		(property "Value" ""
			(at 0 0 180)
			(layer "F.Fab")
			(effects
				(font
					(size 1.27 1.27)
				)
			)
		)
		(duplicate_pad_numbers_are_jumpers no)
		(fp_line
			(start 0.7874 0.4064)
			(end -0.7874 0.4064)
			(stroke
				(width 0.1524)
				(type default)
			)
			(layer "F.SilkS")
		)
		(fp_line
			(start 0.7874 -0.4064)
			(end 0.7874 0.4064)
			(stroke
				(width 0.1524)
				(type default)
			)
			(layer "F.SilkS")
		)
		(fp_line
			(start -0.7874 0.4064)
			(end -0.7874 -0.4064)
			(stroke
				(width 0.1524)
				(type default)
			)
			(layer "F.SilkS")
		)
		(fp_line
			(start -0.7874 -0.4064)
			(end 0.7874 -0.4064)
			(stroke
				(width 0.1524)
				(type default)
			)
			(layer "F.SilkS")
		)
		(fp_line
			(start 0.67945 0.3048)
			(end 0.120396 0.3048)
			(stroke
				(width 0.1)
				(type default)
			)
			(layer "F.Fab")
		)
		(fp_line
			(start 0.67945 -0.3048)
			(end 0.67945 0.3048)
			(stroke
				(width 0.1)
				(type default)
			)
			(layer "F.Fab")
		)
		(fp_line
			(start 0.12065 -0.2794)
			(end 0.12065 -0.3048)
			(stroke
				(width 0.1)
				(type default)
			)
			(layer "F.Fab")
		)
		(fp_line
			(start 0.12065 -0.3048)
			(end 0.67945 -0.3048)
			(stroke
				(width 0.1)
				(type default)
			)
			(layer "F.Fab")
		)
		(fp_line
			(start 0.120396 0.3048)
			(end 0.120396 0.2794)
			(stroke
				(width 0.1)
				(type default)
			)
			(layer "F.Fab")
		)
		(fp_line
			(start 0.120396 0.2794)
			(end -0.12065 0.2794)
			(stroke
				(width 0.1)
				(type default)
			)
			(layer "F.Fab")
		)
		(fp_line
			(start -0.12065 0.3048)
			(end -0.67945 0.3048)
			(stroke
				(width 0.1)
				(type default)
			)
			(layer "F.Fab")
		)
		(fp_line
			(start -0.12065 0.2794)
			(end -0.12065 0.3048)
			(stroke
				(width 0.1)
				(type default)
			)
			(layer "F.Fab")
		)
		(fp_line
			(start -0.12065 -0.2794)
			(end 0.12065 -0.2794)
			(stroke
				(width 0.1)
				(type default)
			)
			(layer "F.Fab")
		)
		(fp_line
			(start -0.12065 -0.305054)
			(end -0.12065 -0.2794)
			(stroke
				(width 0.1)
				(type default)
			)
			(layer "F.Fab")
		)
		(fp_line
			(start -0.67945 0.3048)
			(end -0.67945 -0.305054)
			(stroke
				(width 0.1)
				(type default)
			)
			(layer "F.Fab")
		)
		(fp_line
			(start -0.67945 -0.305054)
			(end -0.12065 -0.305054)
			(stroke
				(width 0.1)
				(type default)
			)
			(layer "F.Fab")
		)
		(pad "1" smd circle
			(at -0.40005 0 180)
			(size 0 0)
			(layers "F.Cu" "F.Mask" "F.Paste")
			(net "FM_P2E_EQA1")
		)
		(pad "2" smd circle
			(at 0.40005 0 180)
			(size 0 0)
			(layers "F.Cu" "F.Mask" "F.Paste")
			(net "GND")
		)
	)
)
